# T6G (Grand Teton) — schematic netlist excerpt (pin names and nets, part order shuffled) for the footprints in the layout excerpt that follows; sources: Cadence DE-HDL packaged netlist, KiCad conversion of 04192023_DAF0TMB3IC0_F0TG_MB_C_brd_V02_OCP.brd

R2659  Q_RES  0 5% CHIP  pkg 0402LF  page 28 : A = CLK_100M_CPU0_CLK11_R_DP ; B = CLK_100M_CPU0_CLK11_DP
TP8  TP  NA  pkg TP  page 27 : TP = VSENSE_PVDD11_S3_P0_DP
C685  Q_CAP_DIFFBUS  DIFF BUS_0.22UF 6.3V 20% X6S  pkg C0201  page 67 : \1\ = P5E_CPU1_G1_TX_C_DP<12> ; \2\ = P5E_CPU1_G1_TX_DP<12>
PC549_C0P0_4  Q_CAP  2.2UF 10V 10% X6S  pkg C0402  page 195 : A = PVDDCR_CPU0_P0_PVCC ; B = GND

(kicad_pcb
	(version 20260206)
	(generator "pcbnew")
	(generator_version "10.0")
	(general
		(thickness 1.6)
		(legacy_teardrops no)
	)
	(paper "A4")
	(title_block
		(title "04192023_DAF0TMB3IC0_F0TG_MB_C_brd_V02_OCP.brd")
		(comment 1 "Grand Teton / footprints 3564-3567 of 8354")
	)
	(layers
		(0 "F.Cu" signal "TOP")
		(4 "In1.Cu" signal "GND")
		(6 "In2.Cu" signal "IN1")
		(8 "In3.Cu" signal "GND1")
		(10 "In4.Cu" signal "IN2")
		(12 "In5.Cu" signal "GND2")
		(14 "In6.Cu" signal "IN3")
		(16 "In7.Cu" signal "GND3")
		(18 "In8.Cu" signal "VCC")
		(20 "In9.Cu" signal "VCC1")
		(22 "In10.Cu" signal "GND4")
		(24 "In11.Cu" signal "IN4")
		(26 "In12.Cu" signal "GND5")
		(28 "In13.Cu" signal "IN5")
		(30 "In14.Cu" signal "GND6")
		(32 "In15.Cu" signal "IN6")
		(34 "In16.Cu" signal "GND7")
		(2 "B.Cu" signal "BOTTOM")
		(9 "F.Adhes" user "F.Adhesive")
		(11 "B.Adhes" user "B.Adhesive")
		(13 "F.Paste" user "Package Geometry/Pastemask Top")
		(15 "B.Paste" user "Package Geometry/Pastemask Bottom")
		(5 "F.SilkS" user "Ref Des/Silkscreen Top")
		(7 "B.SilkS" user "Ref Des/Silkscreen Bottom")
		(1 "F.Mask" user "Board Geometry/Soldermask Top")
		(3 "B.Mask" user "Board Geometry/Soldermask Bottom")
		(17 "Dwgs.User" user "User.Drawings")
		(19 "Cmts.User" user "User.Comments")
		(21 "Eco1.User" user "User.Eco1")
		(23 "Eco2.User" user "User.Eco2")
		(25 "Edge.Cuts" user "Board Geometry/Outline")
		(27 "Margin" user)
		(31 "F.CrtYd" user "Package Geometry/Place Bound Top")
		(29 "B.CrtYd" user "Package Geometry/Place Bound Bottom")
		(35 "F.Fab" user "Ref Des/Assembly Top")
		(33 "B.Fab" user "Ref Des/Assembly Bottom")
	)
	(footprint ""
		(layer "F.Cu")
		(at 366.403128 -324.29704 90)
		(property "Reference" "R2659"
			(at 0 0 90)
			(layer "F.SilkS")
			(hide yes)
			(effects
				(font
					(size 1.27 1.27)
				)
			)
		)
		(property "Value" ""
			(at 0 0 90)
			(layer "F.Fab")
			(effects
				(font
					(size 1.27 1.27)
				)
			)
		)
		(duplicate_pad_numbers_are_jumpers no)
		(fp_line
			(start -0.34544 -0.4064)
			(end 0.39116 -0.4064)
			(stroke
				(width 0.1524)
				(type default)
			)
			(layer "F.SilkS")
		)
		(fp_line
			(start 0.7874 0.017272)
			(end 0.7874 0.4064)
			(stroke
				(width 0.1524)
				(type default)
			)
			(layer "F.SilkS")
		)
		(fp_line
			(start 0.7874 0.4064)
			(end -0.7874 0.4064)
			(stroke
				(width 0.1524)
				(type default)
			)
			(layer "F.SilkS")
		)
		(fp_line
			(start -0.7874 0.4064)
			(end -0.7874 0.068072)
			(stroke
				(width 0.1524)
				(type default)
			)
			(layer "F.SilkS")
		)
		(fp_line
			(start -0.12065 -0.305054)
			(end -0.12065 -0.2794)
			(stroke
				(width 0.1)
				(type default)
			)
			(layer "F.Fab")
		)
		(fp_line
			(start -0.67945 -0.305054)
			(end -0.12065 -0.305054)
			(stroke
				(width 0.1)
				(type default)
			)
			(layer "F.Fab")
		)
		(fp_line
			(start 0.67945 -0.3048)
			(end 0.67945 0.3048)
			(stroke
				(width 0.1)
				(type default)
			)
			(layer "F.Fab")
		)
		(fp_line
			(start 0.12065 -0.3048)
			(end 0.67945 -0.3048)
			(stroke
				(width 0.1)
				(type default)
			)
			(layer "F.Fab")
		)
		(fp_line
			(start 0.12065 -0.2794)
			(end 0.12065 -0.3048)
			(stroke
				(width 0.1)
				(type default)
			)
			(layer "F.Fab")
		)
		(fp_line
			(start -0.12065 -0.2794)
			(end 0.12065 -0.2794)
			(stroke
				(width 0.1)
				(type default)
			)
			(layer "F.Fab")
		)
		(fp_line
			(start 0.120396 0.2794)
			(end -0.12065 0.2794)
			(stroke
				(width 0.1)
				(type default)
			)
			(layer "F.Fab")
		)
		(fp_line
			(start -0.12065 0.2794)
			(end -0.12065 0.3048)
			(stroke
				(width 0.1)
				(type default)
			)
			(layer "F.Fab")
		)
		(fp_line
			(start 0.67945 0.3048)
			(end 0.120396 0.3048)
			(stroke
				(width 0.1)
				(type default)
			)
			(layer "F.Fab")
		)
		(fp_line
			(start 0.120396 0.3048)
			(end 0.120396 0.2794)
			(stroke
				(width 0.1)
				(type default)
			)
			(layer "F.Fab")
		)
		(fp_line
			(start -0.12065 0.3048)
			(end -0.67945 0.3048)
			(stroke
				(width 0.1)
				(type default)
			)
			(layer "F.Fab")
		)
		(fp_line
			(start -0.67945 0.3048)
			(end -0.67945 -0.305054)
			(stroke
				(width 0.1)
				(type default)
			)
			(layer "F.Fab")
		)
		(pad "1" smd circle
			(at -0.40005 0 90)
			(size 0 0)
			(layers "F.Cu" "F.Mask" "F.Paste")
			(net "CLK_100M_CPU0_CLK11_R_DP")
		)
		(pad "2" smd circle
			(at 0.40005 0 90)
			(size 0 0)
			(layers "F.Cu" "F.Mask" "F.Paste")
			(net "CLK_100M_CPU0_CLK11_DP")
		)
	)
	(footprint ""
		(layer "F.Cu")
		(at 24.804878 -17.623536 90)
		(property "Reference" "C685"
			(at 0 0 90)
			(layer "F.SilkS")
			(hide yes)
			(effects
				(font
					(size 1.27 1.27)
				)
			)
		)
		(property "Value" ""
			(at 0 0 90)
			(layer "F.Fab")
			(effects
				(font
					(size 1.27 1.27)
				)
			)
		)
		(duplicate_pad_numbers_are_jumpers no)
		(fp_line
			(start 0.299974 -0.150114)
			(end 0.299974 0.150114)
			(stroke
				(width 0.1)
				(type default)
			)
			(layer "F.Fab")
		)
		(fp_line
			(start -0.299974 -0.150114)
			(end 0.299974 -0.150114)
			(stroke
				(width 0.1)
				(type default)
			)
			(layer "F.Fab")
		)
		(fp_line
			(start 0.299974 0.150114)
			(end -0.299974 0.150114)
			(stroke
				(width 0.1)
				(type default)
			)
			(layer "F.Fab")
		)
		(fp_line
			(start -0.299974 0.150114)
			(end -0.299974 -0.150114)
			(stroke
				(width 0.1)
				(type default)
			)
			(layer "F.Fab")
		)
		(pad "1" smd rect
			(at -0.2667 0 90)
			(size 0.3048 0.381)
			(layers "F.Cu" "F.Mask" "F.Paste")
			(net "P5E_CPU1_G1_TX_C_DP<12>")
		)
		(pad "2" smd rect
			(at 0.2667 0 90)
			(size 0.3048 0.381)
			(layers "F.Cu" "F.Mask" "F.Paste")
			(net "P5E_CPU1_G1_TX_DP<12>")
		)
	)
	(footprint ""
		(layer "F.Cu")
		(at 413.977582 -333.271114)
		(property "Reference" "TP8"
			(at -5.141722 -0.386588 0)
			(unlocked yes)
			(layer "F.SilkS")
			(effects
				(font
					(size 0.7874 0.5842)
					(thickness 0.1524)
				)
				(justify left)
			)
		)
		(property "Value" ""
			(at 0 0 0)
			(layer "F.Fab")
			(effects
				(font
					(size 1.27 1.27)
				)
			)
		)
		(duplicate_pad_numbers_are_jumpers no)
		(pad "1" smd circle
			(at 0 0)
			(size 0.762 0.762)
			(layers "F.Cu" "F.Mask" "F.Paste")
			(net "VSENSE_PVDD11_S3_P0_DP")
		)
	)
	(footprint ""
		(layer "F.Cu")
		(at 393.092178 -182.745634 90)
		(property "Reference" "PC549_C0P0_4"
			(at 0 0 90)
			(layer "F.SilkS")
			(hide yes)
			(effects
				(font
					(size 1.27 1.27)
				)
			)
		)
		(property "Value" ""
			(at 0 0 90)
			(layer "F.Fab")
			(effects
				(font
					(size 1.27 1.27)
				)
			)
		)
		(duplicate_pad_numbers_are_jumpers no)
		(fp_line
			(start 0.7874 -0.4064)
			(end 0.7874 0.4064)
			(stroke
				(width 0.1524)
				(type default)
			)
			(layer "F.SilkS")
		)
		(fp_line
			(start -0.7874 -0.4064)
			(end 0.7874 -0.4064)
			(stroke
				(width 0.1524)
				(type default)
			)
			(layer "F.SilkS")
		)
		(fp_line
			(start 0.7874 0.4064)
			(end -0.7874 0.4064)
			(stroke
				(width 0.1524)
				(type default)
			)
			(layer "F.SilkS")
		)
		(fp_line
			(start -0.7874 0.4064)
			(end -0.7874 -0.4064)
			(stroke
				(width 0.1524)
				(type default)
			)
			(layer "F.SilkS")
		)
		(fp_line
			(start -0.12065 -0.305054)
			(end -0.12065 -0.2794)
			(stroke
				(width 0.1)
				(type default)
			)
			(layer "F.Fab")
		)
		(fp_line
			(start -0.67945 -0.305054)
			(end -0.12065 -0.305054)
			(stroke
				(width 0.1)
				(type default)
			)
			(layer "F.Fab")
		)
		(fp_line
			(start 0.67945 -0.3048)
			(end 0.67945 0.3048)
			(stroke
				(width 0.1)
				(type default)
			)
			(layer "F.Fab")
		)
		(fp_line
			(start 0.12065 -0.3048)
			(end 0.67945 -0.3048)
			(stroke
				(width 0.1)
				(type default)
			)
			(layer "F.Fab")
		)
		(fp_line
			(start 0.12065 -0.2794)
			(end 0.12065 -0.3048)
			(stroke
				(width 0.1)
				(type default)
			)
			(layer "F.Fab")
		)
		(fp_line
			(start -0.12065 -0.2794)
			(end 0.12065 -0.2794)
			(stroke
				(width 0.1)
				(type default)
			)
			(layer "F.Fab")
		)
		(fp_line
			(start 0.120396 0.2794)
			(end -0.12065 0.2794)
			(stroke
				(width 0.1)
				(type default)
			)
			(layer "F.Fab")
		)
		(fp_line
			(start -0.12065 0.2794)
			(end -0.12065 0.3048)
			(stroke
				(width 0.1)
				(type default)
			)
			(layer "F.Fab")
		)
		(fp_line
			(start 0.67945 0.3048)
			(end 0.120396 0.3048)
			(stroke
				(width 0.1)
				(type default)
			)
			(layer "F.Fab")
		)
		(fp_line
			(start 0.120396 0.3048)
			(end 0.120396 0.2794)
			(stroke
				(width 0.1)
				(type default)
			)
			(layer "F.Fab")
		)
		(fp_line
			(start -0.12065 0.3048)
			(end -0.67945 0.3048)
			(stroke
				(width 0.1)
				(type default)
			)
			(layer "F.Fab")
		)
		(fp_line
			(start -0.67945 0.3048)
			(end -0.67945 -0.305054)
			(stroke
				(width 0.1)
				(type default)
			)
			(layer "F.Fab")
		)
		(pad "1" smd circle
			(at -0.40005 0 90)
			(size 0 0)
			(layers "F.Cu" "F.Mask" "F.Paste")
			(net "PVDDCR_CPU0_P0_PVCC")
		)
		(pad "2" smd circle
			(at 0.40005 0 90)
			(size 0 0)
			(layers "F.Cu" "F.Mask" "F.Paste")
			(net "GND")
		)
	)
)
